FILE_TYPE = CONNECTIVITY;
{Allegro Design Entry HDL 16.6-p007 (v16-6-112F) 10/10/2012}
"PAGE_NUMBER" = 222;
0"NC";
1"GND\g";
2"GND\g";
3"GND\g";
4"GND\g";
5"GND\g";
6"GND\g";
7"GND\g";
8"P3V3\g";
9"PVTT_DEF\g";
10"GND\g";
11"PVTT_DEF\g";
12"GND\g";
13"PVDDQ_DEF\g";
14"P3V3\g";
15"GND\g";
16"VR_PVTT_DEF_BIAS";
17"VR_PVTT_DEF_SNS";
18"PWRGD_PVTT_DEF_CPU0_R";
19"PWRGD_PVTT_CPU0";
20"FM_PVTT_DEF_EN_R";
21"VSENSE_PVDDQ_DEF_VTT";
22"PWRGD_PVDDQ_DEF_R";
23"VR_PVTT_DEF_VREF";
%"GND"
"1","(-1150,-1075)","0","mstr_symbols","I1";
;
VOLTAGE"0.0V"
SIZE"1B"
CDS_LIB"mstr_symbols"
BODY_TYPE"PLUMBING"
HDL_POWER"GND";
"A\NAC"1;
%"RES"
"1","(-650,1300)","0","mstr_discrete","I10";
;
PACK_TYPE"0402"
MATERIAL"CHIP"
WATTAGE"1/16W"
VALUE"0.0"
TOLERANCE"5%"
PART_NUMBER"G21497-005"
LOCATION"R6L11"
CDS_SEC"1"
ROOM"VTT_DEF_PWR_VR"
BOM_COST"MEM_VRD_VTT_DEF"
CDS_LOCATION"R6L11"
CDS_LIB"mstr_discrete"
SEC_TYPE"0402"
SEC"1";
"B"
$PN"2"16;
"A"
$PN"1"14;
%"GND"
"1","(-325,800)","0","mstr_symbols","I11";
;
CDS_LIB"mstr_symbols"
VOLTAGE"0.0V"
SIZE"1B"
BODY_TYPE"PLUMBING"
HDL_POWER"GND";
"A\NAC"2;
%"CAP"
"1","(-325,1050)","0","mstr_discrete","I12";
;
PACK_TYPE"0402"
PART_NUMBER"D97712-011"
TOLERANCE"10%"
MATERIAL"X6S"
VALUE"1.0UF"
LOCATION"C4A10"
VOLTAGE"16V"
CDS_SEC"1"
CDS_LOCATION"C4A10"
CDS_LIB"mstr_discrete"
ROOM"VTT_DEF_PWR_VR"
BOM_COST"MEM_VRD_VTT_DEF"
SEC_TYPE"0402"
SEC"1";
"A"
$PN"1"16;
"B"
$PN"2"2;
%"MIC5166"
"1","(775,600)","0","mstr_vreg","I13";
;
PART_NUMBER"H55101-001"
MATERIAL"IC"
LOCATION"EU4A1"
CDS_SEC"1"
BOM_COST"MEM_VRD_VTT_DEF"
PACK_TYPE"DFN"
SEC_TYPE"DFN"
SEC"1"
CDS_LOCATION"EU4A1"
ROOM"VTT_DEF_PWR_VR"
CDS_LMAN_SYM_OUTLINE"-250,350,250,-350"
CDS_LIB"mstr_vreg";
"THPAD"
$PN"11"5;
"VTT"
$PN"9"11;
"PGND"
$PN"8"5;
"SNS"
$PN"6"17;
"VDDQ"
$PN"4"21;
"PG"
$PN"5"18;
"AGND"
$PN"3"5;
"BIAS"
$PN"2"16;
"VREF"
$PN"1"23;
"VIN"
$PN"10"13;
"EN"
$PN"7"20;
%"GND"
"1","(-750,1650)","0","mstr_symbols","I14";
;
BOM_COST"MEM_VRD_VTT_DEF"
ROOM"VTT_DEF_PWR_VR"
VOLTAGE"0.0V"
SIZE"1B"
CDS_LIB"mstr_symbols"
BODY_TYPE"PLUMBING"
HDL_POWER"GND";
"A\NAC"3;
%"CAP"
"1","(-750,1900)","0","mstr_discrete","I15";
;
PART_NUMBER"E15431-001"
PACK_TYPE"0603LF"
MATERIAL"X6S"
TOLERANCE"20%"
LOCATION"C6L4"
VALUE"10UF"
VOLTAGE"4V"
CDS_SEC"1"
CDS_LIB"mstr_discrete"
CDS_LOCATION"C6L4"
SEC_TYPE"0603LF"
BOM_COST"MEM_VRD_VTT_DEF"
SEC"1"
ROOM"VTT_DEF_PWR_VR";
"A"
$PN"1"13;
"B"
$PN"2"3;
%"GND"
"1","(-325,1650)","0","mstr_symbols","I16";
;
ROOM"VTT_DEF_PWR_VR"
BOM_COST"MEM_VRD_VTT_DEF"
VOLTAGE"0.0V"
CDS_LIB"mstr_symbols"
SIZE"1B"
BODY_TYPE"PLUMBING"
HDL_POWER"GND";
"A\NAC"4;
%"CAP"
"1","(-325,1925)","0","mstr_discrete","I17";
;
VOLTAGE"4V"
TOLERANCE"20%"
MATERIAL"X6S"
VALUE"10UF"
PART_NUMBER"E15431-001"
PACK_TYPE"0603LF"
LOCATION"C6L3"
CDS_SEC"1"
CDS_LIB"mstr_discrete"
ROOM"VTT_DEF_PWR_VR"
CDS_LOCATION"C6L3"
SEC"1"
BOM_COST"MEM_VRD_VTT_DEF"
SEC_TYPE"0603LF";
"A"
$PN"1"13;
"B"
$PN"2"4;
%"GND"
"1","(1225,125)","0","mstr_symbols","I18";
;
CDS_LIB"mstr_symbols"
SIZE"1B"
VOLTAGE"0.0V"
BODY_TYPE"PLUMBING"
HDL_POWER"GND";
"A\NAC"5;
%"GND"
"1","(1625,125)","0","mstr_symbols","I19";
;
VOLTAGE"0.0V"
CDS_LIB"mstr_symbols"
SIZE"1B"
BODY_TYPE"PLUMBING"
HDL_POWER"GND";
"A\NAC"6;
%"CAP"
"1","(-1150,-850)","2","mstr_discrete","I2";
;
PART_NUMBER"A36096-046"
PACK_TYPE"0402LF"
TOLERANCE"10%"
VALUE"1000PF"
MATERIAL"EMPTY"
VOLTAGE"50V"
LOCATION"C4A2"
CDS_SEC"1"
BOM_COST"MEM_VRD_VTT_DEF"
CDS_LOCATION"C4A2"
ROOM"VTT_DEF_PWR_VR"
CDS_LIB"mstr_discrete"
SEC_TYPE"0402LF"
SEC"1";
"A"
$PN"1"20;
"B"
$PN"2"1;
%"CAP"
"1","(1625,400)","0","mstr_discrete","I20";
;
LOCATION"C4A9"
PART_NUMBER"D97712-011"
MATERIAL"X6S"
VALUE"1.0UF"
VOLTAGE"16V"
TOLERANCE"10%"
PACK_TYPE"0402"
CDS_SEC"1"
CDS_LIB"mstr_discrete"
SEC"1"
BOM_COST"MEM_VRD_VTT_DEF"
SEC_TYPE"0402"
ROOM"VTT_DEF_PWR_VR"
CDS_LOCATION"C4A9";
"A"
$PN"1"23;
"B"
$PN"2"6;
%"GND"
"1","(3075,925)","0","mstr_symbols","I21";
;
VOLTAGE"0.0V"
SIZE"1B"
CDS_LIB"mstr_symbols"
BODY_TYPE"PLUMBING"
HDL_POWER"GND";
"A\NAC"7;
%"CAP"
"1","(3075,1175)","0","mstr_discrete","I22";
;
PACK_TYPE"0402LF"
PART_NUMBER"A36096-046"
LOCATION"C4A12"
MATERIAL"X7R"
TOLERANCE"10%"
VOLTAGE"50V"
VALUE"1000PF"
CDS_SEC"1"
CDS_LIB"mstr_discrete"
CDS_LOCATION"C4A12"
ROOM"VTT_DEF_PWR_VR"
SEC_TYPE"0402LF"
SEC"1"
BOM_COST"MEM_VRD_VTT_DEF";
"A"
$PN"1"18;
"B"
$PN"2"7;
%"RES"
"2","(2500,1650)","0","mstr_discrete","I23";
;
PACK_TYPE"0402"
PART_NUMBER"G21796-016"
MATERIAL"CHIP"
WATTAGE"1/16W"
LOCATION"R6L9"
TOLERANCE"1%"
VALUE"10.0K"
CDS_SEC"1"
ROOM"VTT_DEF_PWR_VR"
CDS_LOCATION"R6L9"
SEC"1"
SEC_TYPE"0402"
BOM_COST"MEM_VRD_VTT_DEF"
CDS_LIB"mstr_discrete";
"A"
$PN"1"8;
"B"
$PN"2"18;
%"P3V3"
"1","(2500,1875)","0","mstr_symbols","I24";
;
SIZE"1B"
VOLTAGE"3.3V"
CDS_LIB"mstr_symbols"
BODY_TYPE"PLUMBING"
HDL_POWER"P3V3";
"G\NAC"8;
%"PVTT_DEF"
"1","(2750,3200)","0","mstr_symbols","I25";
;
VOLTAGE"0.6V"
CDS_LIB"mstr_symbols"
BOM_COST"MEM_VRD_PVDDQ_AB"
ROOM"VTT_DEF_PWR_VR"
BODY_TYPE"PLUMBING"
HDL_POWER"PVTT_DEF";
"G\NAC"9;
%"CAP"
"1","(3200,575)","0","mstr_discrete","I28";
;
GROUP"PWR_MLCC_CAP"
VALUE"22UF"
PART_NUMBER"C95333-002"
TOLERANCE"20%"
MATERIAL"X6S"
VOLTAGE"4V"
LOCATION"C4A1"
PACK_TYPE"0805LF"
CDS_SEC"1"
CDS_LIB"mstr_discrete"
CDS_LOCATION"C4A1"
ROOM"VTT_DEF_PWR_VR"
SEC_TYPE"0805LF"
BOM_COST"MEM_VRD_VTT_DEF"
SEC"1";
"A"
$PN"1"11;
"B"
$PN"2"10;
%"GND"
"1","(3200,175)","0","mstr_symbols","I29";
;
VOLTAGE"0.0V"
SIZE"1B"
CDS_LIB"mstr_symbols"
BODY_TYPE"PLUMBING"
HDL_POWER"GND";
"A\NAC"10;
%"SHUNT"
"1","(4175,-425)","0","mstr_misc","I30";
;
PART_NUMBER"N_A"
LOCATION"SH5L1"
CDS_SEC"1"
CDS_LOCATION"SH5L1"
PACK_TYPE"SH0201"
PIN_SHORT"A:B"
MATERIAL"EMPTY"
CDS_LIB"mstr_misc"
SEC"1"
SEC_TYPE"SH0201";
"A"
$PN"1"17;
"B"
$PN"2"11;
%"RES"
"1","(3475,1375)","0","mstr_discrete","I31";
;
PART_NUMBER"G21796-074"
PACK_TYPE"0402"
TOLERANCE"1%"
LOCATION"R4A6"
MATERIAL"CHIP"
WATTAGE"1/16W"
VALUE"33.2"
CDS_SEC"1"
CDS_LOCATION"R4A6"
CDS_LIB"mstr_discrete"
SEC_TYPE"0402"
SEC"1";
"B"
$PN"2"19;
"A"
$PN"1"18;
%"PVTT_DEF"
"1","(4750,1125)","0","mstr_symbols","I34";
;
VOLTAGE"0.6V"
CDS_LIB"mstr_symbols"
BODY_TYPE"PLUMBING"
HDL_POWER"PVTT_DEF";
"G\NAC"11;
%"GND"
"1","(2750,2275)","0","mstr_symbols","I35";
;
HDL_POWER"GND"
BODY_TYPE"PLUMBING"
CDS_LIB"mstr_symbols"
BOM_COST"MEM_VRD_PVDDQ_AB"
SIZE"1B"
VOLTAGE"0.0V"
ROOM"VTT_DEF_PWR_VR";
"A\NAC"12;
%"PVDDQ_DEF"
"1","(-2225,2325)","0","mstr_symbols","I37";
;
VOLTAGE"1.2V"
CDS_LIB"mstr_symbols"
BODY_TYPE"PLUMBING"
HDL_POWER"PVDDQ_DEF";
"G\NAC"13;
%"RES"
"1","(-1300,-325)","0","mstr_discrete","I4";
;
PACK_TYPE"0402"
MATERIAL"CHIP"
WATTAGE"1/16W"
VALUE"0.0"
TOLERANCE"5%"
PART_NUMBER"G21497-005"
LOCATION"R4A2"
CDS_SEC"1"
CDS_LIB"mstr_discrete"
SEC"1"
CDS_LOCATION"R4A2"
ROOM"VTT_DEF_PWR_VR"
BOM_COST"MEM_VRD_VTT_DEF"
SEC_TYPE"0402";
"B"
$PN"2"20;
"A"
$PN"1"22;
%"CAP_A"
"1","(3500,2825)","0","dev_discrete","I41";
;
GROUP"PWR_MLCC_CAP"
LOCATION"C5M13"
PACK_TYPE"0603V"
PART_NUMBER"602433-106"
MATERIAL"X5R"
TOLERANCE"20%"
VALUE"47UF"
VOLTAGE"4V"
SEC"1"
CDS_SEC"1"
SEC_TYPE"0603V"
CDS_LOCATION"C5M13"
CDS_LIB"dev_discrete";
"B"
$PN"2"12;
"A"
$PN"1"9;
%"CAP"
"1","(3100,2825)","0","mstr_discrete","I44";
;
GROUP"PWR_MLCC_CAP"
PART_NUMBER"602433-112"
PACK_TYPE"0805"
TOLERANCE"20%"
NEW_MATERIAL"X6S"
LOCATION"C5L5"
VALUE"100UF"
VOLTAGE"4V"
NEW_PN"078.1071T.M002"
CDS_LOCATION"C5L5"
MATERIAL"X5R"
SEC"1"
SEC_TYPE"0805"
ROOM"VDDQ_ABC_PWR_VR"
BOM_COST"MEM_VRD_PVDDQ_CD"
CDS_LIB"mstr_discrete"
CDS_SEC"1";
"A"
$PN"1"9;
"B"
$PN"2"12;
%"CAP"
"1","(2750,2825)","0","mstr_discrete","I45";
;
GROUP"PWR_MLCC_CAP"
PART_NUMBER"602433-112"
NEW_MATERIAL"X6S"
LOCATION"C5L4"
VALUE"100UF"
VOLTAGE"4V"
TOLERANCE"20%"
NEW_PN"078.1071T.M002"
PACK_TYPE"0805"
CDS_LOCATION"C5L4"
MATERIAL"X5R"
SEC"1"
SEC_TYPE"0805"
ROOM"VDDQ_ABC_PWR_VR"
BOM_COST"MEM_VRD_PVDDQ_CD"
CDS_LIB"mstr_discrete"
CDS_SEC"1";
"A"
$PN"1"9;
"B"
$PN"2"12;
%"CAP"
"1","(4100,575)","0","mstr_discrete","I46";
;
VOLTAGE"4V"
LOCATION"C4W5"
VALUE"100UF"
TOLERANCE"20%"
PART_NUMBER"602433-112"
PACK_TYPE"0805"
GROUP"PWR_MLCC_CAP"
NEW_MATERIAL"X6S"
NEW_PN"078.1071T.M002"
CDS_LOCATION"C4W5"
MATERIAL"X5R"
SEC"1"
SEC_TYPE"0805"
ROOM"VDDQ_ABC_PWR_VR"
BOM_COST"MEM_VRD_PVDDQ_CD"
CDS_LIB"mstr_discrete"
CDS_SEC"1";
"A"
$PN"1"11;
"B"
$PN"2"10;
%"RES"
"2","(-1100,200)","2","mstr_discrete","I5";
;
PACK_TYPE"0402"
PART_NUMBER"G21796-021"
MATERIAL"EMPTY"
WATTAGE"1/16W"
TOLERANCE"1%"
VALUE"1.0M"
LOCATION"R6L4"
CDS_SEC"1"
CDS_LIB"mstr_discrete"
CDS_LOCATION"R6L4"
BOM_COST"MEM_VRD_VTT_DEF"
SEC_TYPE"0402"
SEC"1"
ROOM"VTT_DEF_PWR_VR";
"A"
$PN"1"14;
"B"
$PN"2"20;
%"RES"
"2","(-1500,1100)","1","mstr_discrete","I6";
;
PACK_TYPE"0402"
MATERIAL"CHIP"
VALUE"0.0"
WATTAGE"1/16W"
TOLERANCE"5%"
LOCATION"R6L10"
PART_NUMBER"G21497-005"
CDS_SEC"1"
CDS_LIB"mstr_discrete"
CDS_LOCATION"R6L10"
SEC_TYPE"0402"
NO_XNET_CONNECTION"1"
SEC"1"
ROOM"VTT_DEF_PWR_VR"
BOM_COST"MEM_VRD_VTT_DEF";
"A"
$PN"1"13;
"B"
$PN"2"21;
%"P3V3"
"1","(-1375,1700)","0","mstr_symbols","I7";
;
VOLTAGE"3.3V"
SIZE"1B"
CDS_LIB"mstr_symbols"
BODY_TYPE"PLUMBING"
HDL_POWER"P3V3";
"G\NAC"14;
%"GND"
"1","(-675,325)","0","mstr_symbols","I8";
;
VOLTAGE"0.0V"
CDS_LIB"mstr_symbols"
SIZE"1B"
BODY_TYPE"PLUMBING"
HDL_POWER"GND";
"A\NAC"15;
%"CAP"
"1","(-675,525)","0","mstr_discrete","I9";
;
PACK_TYPE"0603"
PART_NUMBER"E15431-003"
MATERIAL"X6S"
TOLERANCE"10%"
VOLTAGE"6.3V"
VALUE"4.7UF"
LOCATION"C4A11"
CDS_SEC"1"
CDS_LIB"mstr_discrete"
CDS_LOCATION"C4A11"
SEC_TYPE"0603"
SEC"1"
ROOM"VTT_DEF_PWR_VR";
"A"
$PN"1"21;
"B"
$PN"2"15;
END.
